# BASEBOARD_FAB2 (Tioga Pass) — schematic netlist excerpt (pin names and nets, part order shuffled) for the footprints in the layout excerpt that follows; sources: Cadence DE-HDL packaged netlist, KiCad conversion of Wiwynn_Tioga_Pass_MB.brd

Q8F1  FET_N  2N7002 FET  pkg SOT23LF  page 154
  GATE  = FM_BACKUP_BIOS_SEL_N
  SRC  = GND
  DRN  = FM_DUAL_BIOS_SEL_N

C22W33  SC22U16V5MX-4-GP  20%  pkg SMD-BCG5  page 212 : \1\ = VR_FET_SW_P12V_STBY_PVCCIO_CPU0 ; \2\ = GND
R6P4  RES  42.2 1.0% EMPTY  pkg 0402  page 103 : A = CLK_100M_CPU0_RC_REFCLK1_DN ; B = GND

(kicad_pcb
	(version 20260206)
	(generator "pcbnew")
	(generator_version "10.0")
	(general
		(thickness 1.6)
		(legacy_teardrops no)
	)
	(paper "A4")
	(title_block
		(title "Wiwynn_Tioga_Pass_MB.brd")
		(comment 1 "Tioga Pass / footprints 2488-2490 of 4770")
	)
	(layers
		(0 "F.Cu" signal "TOP")
		(4 "In1.Cu" signal "L2GND")
		(6 "In2.Cu" signal "L3")
		(8 "In3.Cu" signal "L4GND")
		(10 "In4.Cu" signal "L5")
		(12 "In5.Cu" signal "L6GND")
		(14 "In6.Cu" signal "L7VCC")
		(16 "In7.Cu" signal "L8VCC")
		(18 "In8.Cu" signal "L9GND")
		(20 "In9.Cu" signal "L10")
		(22 "In10.Cu" signal "L11GND")
		(24 "In11.Cu" signal "L12")
		(26 "In12.Cu" signal "L13GND")
		(2 "B.Cu" signal "BOTTOM")
		(9 "F.Adhes" user "F.Adhesive")
		(11 "B.Adhes" user "B.Adhesive")
		(13 "F.Paste" user "Package Geometry/Pastemask Top")
		(15 "B.Paste" user "Package Geometry/Pastemask Bottom")
		(5 "F.SilkS" user "Ref Des/Silkscreen Top")
		(7 "B.SilkS" user "Ref Des/Silkscreen Bottom")
		(1 "F.Mask" user "Board Geometry/Soldermask Top")
		(3 "B.Mask" user "Board Geometry/Soldermask Bottom")
		(17 "Dwgs.User" user "User.Drawings")
		(19 "Cmts.User" user "User.Comments")
		(21 "Eco1.User" user "User.Eco1")
		(23 "Eco2.User" user "User.Eco2")
		(25 "Edge.Cuts" user "Board Geometry/Outline")
		(27 "Margin" user)
		(31 "F.CrtYd" user "Package Geometry/Place Bound Top")
		(29 "B.CrtYd" user "Package Geometry/Place Bound Bottom")
		(35 "F.Fab" user "Ref Des/Assembly Top")
		(33 "B.Fab" user "Ref Des/Assembly Bottom")
	)
	(footprint ""
		(layer "B.Cu")
		(at 385.9276 -65.3288 90)
		(property "Reference" "Q8F1"
			(at -3.42773 -1.1938 180)
			(unlocked yes)
			(layer "B.SilkS")
			(effects
				(font
					(size 0.7874 0.5842)
					(thickness 0.1524)
				)
				(justify left mirror)
			)
		)
		(property "Value" ""
			(at 0 0 90)
			(layer "B.Fab")
			(effects
				(font
					(size 1.27 1.27)
				)
				(justify mirror)
			)
		)
		(duplicate_pad_numbers_are_jumpers no)
		(fp_line
			(start -0.9525 -0.5715)
			(end -1.778 -0.5715)
			(stroke
				(width 0.1524)
				(type default)
			)
			(layer "B.SilkS")
		)
		(fp_line
			(start -1.778 -0.5715)
			(end -1.778 0.3175)
			(stroke
				(width 0.1524)
				(type default)
			)
			(layer "B.SilkS")
		)
		(fp_line
			(start -0.381 0.635)
			(end -0.381 1.27)
			(stroke
				(width 0.1524)
				(type default)
			)
			(layer "B.SilkS")
		)
		(fp_line
			(start -0.9525 2.4765)
			(end -1.778 2.4765)
			(stroke
				(width 0.1524)
				(type default)
			)
			(layer "B.SilkS")
		)
		(fp_line
			(start -1.778 2.4765)
			(end -1.778 1.5875)
			(stroke
				(width 0.1524)
				(type default)
			)
			(layer "B.SilkS")
		)
		(fp_circle
			(center 0.9525 -0.9271)
			(end 0.9525 -0.8001)
			(stroke
				(width 0.254)
				(type default)
			)
			(fill no)
			(layer "B.SilkS")
		)
		(fp_poly
			(pts
				(xy -1.778 2.4765) (xy -0.381 2.4765) (xy -0.381 -0.5715) (xy -1.778 -0.5715)
			)
			(stroke
				(width 0)
				(type default)
			)
			(fill no)
			(layer "B.CrtYd")
		)
		(fp_line
			(start -0.381 -0.5715)
			(end -0.381 2.4765)
			(stroke
				(width 0.1)
				(type default)
			)
			(layer "B.Fab")
		)
		(fp_line
			(start -1.778 -0.5715)
			(end -0.381 -0.5715)
			(stroke
				(width 0.1)
				(type default)
			)
			(layer "B.Fab")
		)
		(fp_line
			(start -0.381 2.4765)
			(end -1.778 2.4765)
			(stroke
				(width 0.1)
				(type default)
			)
			(layer "B.Fab")
		)
		(fp_line
			(start -1.778 2.4765)
			(end -1.778 -0.5715)
			(stroke
				(width 0.1)
				(type default)
			)
			(layer "B.Fab")
		)
		(fp_circle
			(center 0.9525 -0.9271)
			(end 0.9525 -0.8001)
			(stroke
				(width 0.254)
				(type default)
			)
			(fill no)
			(layer "B.Fab")
		)
		(pad "1" smd rect
			(at 0 0 270)
			(size 1.143 0.508)
			(layers "B.Cu" "B.Mask" "B.Paste")
			(net "FM_BACKUP_BIOS_SEL_N")
		)
		(pad "2" smd rect
			(at 0 1.905 270)
			(size 1.143 0.508)
			(layers "B.Cu" "B.Mask" "B.Paste")
			(net "GND")
		)
		(pad "3" smd rect
			(at -2.159 0.9525 270)
			(size 1.143 0.508)
			(layers "B.Cu" "B.Mask" "B.Paste")
			(net "FM_DUAL_BIOS_SEL_N")
		)
	)
	(footprint ""
		(layer "B.Cu")
		(at 169.926 -87.757)
		(property "Reference" "R6P4"
			(at 0 0 0)
			(layer "B.SilkS")
			(hide yes)
			(effects
				(font
					(size 1.27 1.27)
				)
				(justify mirror)
			)
		)
		(property "Value" ""
			(at 0 0 0)
			(layer "B.Fab")
			(effects
				(font
					(size 1.27 1.27)
				)
				(justify mirror)
			)
		)
		(duplicate_pad_numbers_are_jumpers no)
		(fp_poly
			(pts
				(xy 0.2794 -0.1016) (xy -0.2794 -0.1016) (xy -0.2794 0.9906) (xy 0.2794 0.9906)
			)
			(stroke
				(width 0)
				(type default)
			)
			(fill no)
			(layer "B.CrtYd")
		)
		(fp_line
			(start -0.2794 -0.1016)
			(end 0.2794 -0.1016)
			(stroke
				(width 0.1)
				(type default)
			)
			(layer "B.Fab")
		)
		(fp_line
			(start -0.2794 0.9906)
			(end -0.2794 -0.1016)
			(stroke
				(width 0.1)
				(type default)
			)
			(layer "B.Fab")
		)
		(fp_line
			(start 0.2794 -0.1016)
			(end 0.2794 0.9906)
			(stroke
				(width 0.1)
				(type default)
			)
			(layer "B.Fab")
		)
		(fp_line
			(start 0.2794 0.9906)
			(end -0.2794 0.9906)
			(stroke
				(width 0.1)
				(type default)
			)
			(layer "B.Fab")
		)
		(pad "1" smd rect
			(at 0 0 180)
			(size 0.508 0.508)
			(layers "B.Cu" "B.Mask" "B.Paste")
			(net "CLK_100M_CPU0_RC_REFCLK1_DN")
		)
		(pad "2" smd rect
			(at 0 0.889 180)
			(size 0.508 0.508)
			(layers "B.Cu" "B.Mask" "B.Paste")
			(net "GND")
		)
		(zone
			(layer "B.Cu")
			(hatch none 0.5)
			(connect_pads
				(clearance 0)
			)
			(min_thickness 0.25)
			(keepout
				(tracks allowed)
				(vias not_allowed)
				(pads allowed)
				(copperpour not_allowed)
				(footprints allowed)
			)
			(placement
				(enabled no)
				(sheetname "")
			)
			(fill
				(thermal_gap 0.5)
				(thermal_bridge_width 0.5)
				(island_removal_mode 0)
			)
			(polygon
				(pts
					(xy 170.18 -87.503) (xy 169.672 -87.503) (xy 169.672 -87.122) (xy 170.18 -87.122)
				)
			)
		)
		(zone
			(layer "B.Cu")
			(hatch none 0.5)
			(connect_pads
				(clearance 0)
			)
			(min_thickness 0.25)
			(keepout
				(tracks not_allowed)
				(vias allowed)
				(pads allowed)
				(copperpour not_allowed)
				(footprints allowed)
			)
			(placement
				(enabled no)
				(sheetname "")
			)
			(fill
				(thermal_gap 0.5)
				(thermal_bridge_width 0.5)
				(island_removal_mode 0)
			)
			(polygon
				(pts
					(xy 170.18 -87.122) (xy 169.672 -87.122) (xy 169.672 -87.503) (xy 170.18 -87.503)
				)
			)
		)
	)
	(footprint ""
		(layer "B.Cu")
		(at 352.552 -104.267 180)
		(property "Reference" "C22W33"
			(at 0 0 0)
			(layer "B.SilkS")
			(hide yes)
			(effects
				(font
					(size 1.27 1.27)
				)
				(justify mirror)
			)
		)
		(property "Value" "*"
			(at 0.0762 -6.2357 180)
			(unlocked yes)
			(layer "B.Fab")
			(hide yes)
			(effects
				(font
					(size 1.27 1.016)
					(thickness 0.1524)
				)
				(justify mirror)
			)
		)
		(property "Device Type" "SC22U16V5MX-4-GP_SMD-BCG5-SC22A"
			(at 0.0762 -8.2677 180)
			(unlocked yes)
			(layer "B.Fab")
			(hide yes)
			(effects
				(font
					(size 1.27 1.016)
					(thickness 0.1524)
				)
				(justify mirror)
			)
		)
		(duplicate_pad_numbers_are_jumpers no)
		(fp_line
			(start -0.635 0)
			(end 0.635 0)
			(stroke
				(width 0.508)
				(type default)
			)
			(layer "B.SilkS")
		)
		(fp_rect
			(start 0.9652 1.778)
			(end -0.9652 -1.778)
			(stroke
				(width 0)
				(type default)
			)
			(fill no)
			(layer "B.CrtYd")
		)
		(fp_poly
			(pts
				(xy 0.9652 -1.778) (xy -0.9652 -1.778) (xy -0.9652 1.778) (xy 0.9652 1.778)
			)
			(stroke
				(width 0)
				(type default)
			)
			(fill no)
			(layer "B.Fab")
		)
		(pad "1" smd rect
			(at 0 -0.9652)
			(size 1.397 1.143)
			(layers "B.Cu" "B.Mask" "B.Paste")
			(net "VR_FET_SW_P12V_STBY_PVCCIO_CPU0")
		)
		(pad "2" smd rect
			(at 0 0.9652)
			(size 1.397 1.143)
			(layers "B.Cu" "B.Mask" "B.Paste")
			(net "GND")
		)
	)
)
